(kicad_pcb
	(version 20241229)
	(generator "pcbnew")
	(generator_version "9.0")
	(general
		(thickness 1.62)
		(legacy_teardrops no)
	)
	(paper "A3")
	(title_block
		(title "COM Express 7 Baseboard")
		(date "2025-02-04")
		(rev "1.1.2")
		(company "Antmicro Ltd")
		(comment 1 "www.antmicro.com")
		(comment 9 "footprints 245-250 of 802")
	)
	(layers
		(0 "F.Cu" signal)
		(4 "In1.Cu" signal)
		(6 "In2.Cu" signal)
		(8 "In3.Cu" signal)
		(10 "In4.Cu" signal)
		(12 "In5.Cu" signal)
		(14 "In6.Cu" signal)
		(2 "B.Cu" signal)
		(9 "F.Adhes" user "F.Adhesive")
		(11 "B.Adhes" user "B.Adhesive")
		(13 "F.Paste" user)
		(15 "B.Paste" user)
		(5 "F.SilkS" user "F.Silkscreen")
		(7 "B.SilkS" user "B.Silkscreen")
		(1 "F.Mask" user)
		(3 "B.Mask" user)
		(17 "Dwgs.User" user "User.Drawings")
		(19 "Cmts.User" user "User.Comments")
		(21 "Eco1.User" user "User.Eco1")
		(23 "Eco2.User" user "User.Eco2")
		(25 "Edge.Cuts" user)
		(27 "Margin" user)
		(31 "F.CrtYd" user "F.Courtyard")
		(29 "B.CrtYd" user "B.Courtyard")
		(35 "F.Fab" user)
		(33 "B.Fab" user)
	)
	(footprint "antmicro-footprints:TP_SMD_0.75mm"
		(layer "F.Cu")
		(at 149.2 128.71)
		(property "Reference" "TP64"
			(at 0.4 -3.3 90)
			(layer "F.SilkS")
			(effects
				(font
					(size 0.7 0.7)
					(thickness 0.15)
				)
				(justify left bottom)
			)
		)
		(property "Value" "TP_0.75mm_SMD"
			(at 0 1.2 0)
			(layer "F.Fab")
			(effects
				(font
					(size 0.7 0.7)
					(thickness 0.15)
				)
				(justify left bottom)
			)
		)
		(property "Author" "Antmicro"
			(at 0 0 0)
			(layer "F.Fab")
			(hide yes)
			(effects
				(font
					(size 1 1)
					(thickness 0.15)
				)
			)
		)
		(property "License" "Apache-2.0"
			(at 0 0 0)
			(layer "F.Fab")
			(hide yes)
			(effects
				(font
					(size 1 1)
					(thickness 0.15)
				)
			)
		)
		(property "MPN" ""
			(at 0 0 0)
			(layer "F.Fab")
			(hide yes)
			(effects
				(font
					(size 1 1)
					(thickness 0.15)
				)
			)
		)
		(property "Manufacturer" ""
			(at 0 0 0)
			(layer "F.Fab")
			(hide yes)
			(effects
				(font
					(size 1 1)
					(thickness 0.15)
				)
			)
		)
		(property "Public" "False"
			(at 0 0 0)
			(layer "F.Fab")
			(hide yes)
			(effects
				(font
					(size 1 1)
					(thickness 0.15)
				)
			)
		)
		(sheetname "KR to SFI #1")
		(sheetfile "kr_sfi.kicad_sch")
		(attr exclude_from_pos_files exclude_from_bom)
		(fp_circle
			(center 0 0)
			(end 0.475 0)
			(stroke
				(width 0.05)
				(type default)
			)
			(fill no)
			(layer "F.CrtYd")
		)
		(pad "1" smd circle
			(at 0 0)
			(size 0.75 0.75)
			(layers "F.Cu" "F.Mask")
			(net 727 "Net-(U43C-PRBS_{PASS})")
			(pinfunction "1")
			(pintype "passive")
			(teardrops
				(best_length_ratio 0.4)
				(max_length 1)
				(best_width_ratio 0.9)
				(max_width 2)
				(curved_edges yes)
				(filter_ratio 0.9)
				(enabled yes)
				(allow_two_segments yes)
				(prefer_zone_connections yes)
			)
		)
	)
	(footprint "antmicro-footprints:R_0402_1005Metric"
		(layer "F.Cu")
		(at 155.299 161.11 180)
		(descr "Resistor SMD 0402")
		(tags "resistor SMD 0402")
		(property "Reference" "R46"
			(at -6.701 17.5 0)
			(layer "F.SilkS")
			(effects
				(font
					(size 0.7 0.7)
					(thickness 0.15)
				)
				(justify right bottom)
			)
		)
		(property "Value" "R_0R_0402"
			(at -1.011843 1.772047 0)
			(layer "F.Fab")
			(effects
				(font
					(size 0.7 0.7)
					(thickness 0.15)
				)
				(justify right bottom)
			)
		)
		(property "Datasheet" "https://industrial.panasonic.com/cdbs/www-data/pdf/RDA0000/AOA0000C301.pdf"
			(at 0 0 180)
			(layer "F.Fab")
			(hide yes)
			(effects
				(font
					(size 1.27 1.27)
					(thickness 0.15)
				)
			)
		)
		(property "Author" "Antmicro"
			(at 310.598 322.22 0)
			(layer "F.Fab")
			(hide yes)
			(effects
				(font
					(size 1 1)
					(thickness 0.15)
				)
			)
		)
		(property "Current" "1A"
			(at 310.598 322.22 0)
			(layer "F.Fab")
			(hide yes)
			(effects
				(font
					(size 1 1)
					(thickness 0.15)
				)
			)
		)
		(property "License" "Apache-2.0"
			(at 310.598 322.22 0)
			(layer "F.Fab")
			(hide yes)
			(effects
				(font
					(size 1 1)
					(thickness 0.15)
				)
			)
		)
		(property "MPN" "ERJ2GE0R00X"
			(at 310.598 322.22 0)
			(layer "F.Fab")
			(hide yes)
			(effects
				(font
					(size 1 1)
					(thickness 0.15)
				)
			)
		)
		(property "Manufacturer" "Panasonic"
			(at 310.598 322.22 0)
			(layer "F.Fab")
			(hide yes)
			(effects
				(font
					(size 1 1)
					(thickness 0.15)
				)
			)
		)
		(property "Public" "False"
			(at 310.598 322.22 0)
			(layer "F.Fab")
			(hide yes)
			(effects
				(font
					(size 1 1)
					(thickness 0.15)
				)
			)
		)
		(property "Tolerance" ""
			(at 310.598 322.22 0)
			(layer "F.Fab")
			(hide yes)
			(effects
				(font
					(size 1 1)
					(thickness 0.15)
				)
			)
		)
		(property "Val" "0R"
			(at 310.598 322.22 0)
			(layer "F.Fab")
			(hide yes)
			(effects
				(font
					(size 1 1)
					(thickness 0.15)
				)
			)
		)
		(sheetname "2xSFP+")
		(sheetfile "2xSFP+.kicad_sch")
		(attr smd)
		(fp_rect
			(start -0.925 -0.47)
			(end 0.925 0.47)
			(stroke
				(width 0.05)
				(type default)
			)
			(fill no)
			(layer "F.CrtYd")
		)
		(fp_rect
			(start -0.5 -0.25)
			(end 0.5 0.25)
			(stroke
				(width 0.15)
				(type solid)
			)
			(fill no)
			(layer "F.Fab")
		)
		(pad "1" smd roundrect
			(at -0.48 0 180)
			(size 0.59 0.64)
			(layers "F.Cu" "F.Mask" "F.Paste")
			(roundrect_rratio 0.25)
			(net 565 "/2xSFP+/~{LED1_0}")
			(pintype "passive")
			(teardrops
				(best_length_ratio 0.2)
				(max_length 1)
				(best_width_ratio 0.9)
				(max_width 2)
				(curved_edges yes)
				(filter_ratio 0.9)
				(enabled yes)
				(allow_two_segments yes)
				(prefer_zone_connections yes)
			)
		)
		(pad "2" smd roundrect
			(at 0.48 0 180)
			(size 0.59 0.64)
			(layers "F.Cu" "F.Mask" "F.Paste")
			(roundrect_rratio 0.25)
			(net 898 "/2xSFP+/SFP1_LEDY")
			(pintype "passive")
			(teardrops
				(best_length_ratio 0.2)
				(max_length 1)
				(best_width_ratio 0.9)
				(max_width 2)
				(curved_edges yes)
				(filter_ratio 0.9)
				(enabled yes)
				(allow_two_segments yes)
				(prefer_zone_connections yes)
			)
		)
	)
	(footprint "antmicro-footprints:Oscillator_SMD_ECS_2520MV_2.5x2mm"
		(layer "F.Cu")
		(at 308.275 78.41)
		(descr "Miniature Crystal Clock Oscillator ECS 2520MV series")
		(tags "Crystal Clock Oscillator ECS 2520MV SMD")
		(property "Reference" "Y1"
			(at 2.125 1.75 90)
			(layer "F.SilkS")
			(effects
				(font
					(size 0.7 0.7)
					(thickness 0.15)
				)
				(justify left bottom)
			)
		)
		(property "Value" "Oscillator_32.768kHz_ECS_2520MV"
			(at 0 2.499 0)
			(layer "F.Fab")
			(effects
				(font
					(size 0.7 0.7)
					(thickness 0.15)
				)
				(justify left bottom)
			)
		)
		(property "Datasheet" "https://ecsxtal.com/store/pdf/ECS-327MVATX.pdf"
			(at 0 0 0)
			(layer "F.Fab")
			(hide yes)
			(effects
				(font
					(size 1.27 1.27)
					(thickness 0.15)
				)
			)
		)
		(property "Author" "Antmicro"
			(at 0 0 0)
			(layer "F.Fab")
			(hide yes)
			(effects
				(font
					(size 1 1)
					(thickness 0.15)
				)
			)
		)
		(property "License" "Apache-2.0"
			(at 0 0 0)
			(layer "F.Fab")
			(hide yes)
			(effects
				(font
					(size 1 1)
					(thickness 0.15)
				)
			)
		)
		(property "MPN" "ECS-327MVATX-2-CN-TR3"
			(at 0 0 0)
			(layer "F.Fab")
			(hide yes)
			(effects
				(font
					(size 1 1)
					(thickness 0.15)
				)
			)
		)
		(property "Manufacturer" "ECS Inc. International"
			(at 0 0 0)
			(layer "F.Fab")
			(hide yes)
			(effects
				(font
					(size 1 1)
					(thickness 0.15)
				)
			)
		)
		(property "Public" "False"
			(at 0 0 0)
			(layer "F.Fab")
			(hide yes)
			(effects
				(font
					(size 1 1)
					(thickness 0.15)
				)
			)
		)
		(property "Val" "32.768 kHz"
			(at 0 0 0)
			(layer "F.Fab")
			(hide yes)
			(effects
				(font
					(size 1 1)
					(thickness 0.15)
				)
			)
		)
		(sheetname "PCIe misc")
		(sheetfile "pcie_misc.kicad_sch")
		(attr smd)
		(fp_line
			(start -1.111 0.32)
			(end -1.111 -0.32)
			(stroke
				(width 0.15)
				(type solid)
			)
			(layer "F.SilkS")
		)
		(fp_line
			(start -0.172 1.36)
			(end 0.17 1.36)
			(stroke
				(width 0.15)
				(type solid)
			)
			(layer "F.SilkS")
		)
		(fp_line
			(start -0.16 -1.361)
			(end 0.17 -1.361)
			(stroke
				(width 0.15)
				(type solid)
			)
			(layer "F.SilkS")
		)
		(fp_line
			(start 1.11 0.32)
			(end 1.11 -0.32)
			(stroke
				(width 0.15)
				(type solid)
			)
			(layer "F.SilkS")
		)
		(fp_circle
			(center -1.1 -1.5)
			(end -1.049 -1.5)
			(stroke
				(width 0.15)
				(type solid)
			)
			(fill yes)
			(layer "F.SilkS")
		)
		(fp_rect
			(start -1.25 -1.5)
			(end 1.25 1.5)
			(stroke
				(width 0.05)
				(type solid)
			)
			(fill no)
			(layer "F.CrtYd")
		)
		(fp_line
			(start -1 -0.75)
			(end -0.5 -1.25)
			(stroke
				(width 0.15)
				(type solid)
			)
			(layer "F.Fab")
		)
		(fp_rect
			(start 1 1.249)
			(end -1 -1.25)
			(stroke
				(width 0.15)
				(type solid)
			)
			(fill no)
			(layer "F.Fab")
		)
		(pad "1" smd roundrect
			(at -0.725 -0.927)
			(size 0.8 0.9)
			(layers "F.Cu" "F.Mask" "F.Paste")
			(roundrect_rratio 0.25)
			(net 610 "Net-(Y1-EN)")
			(pinfunction "EN")
			(pintype "input")
			(teardrops
				(best_length_ratio 0.2)
				(max_length 1)
				(best_width_ratio 0.9)
				(max_width 2)
				(curved_edges yes)
				(filter_ratio 0.9)
				(enabled yes)
				(allow_two_segments yes)
				(prefer_zone_connections yes)
			)
		)
		(pad "2" smd roundrect
			(at -0.725 0.925)
			(size 0.8 0.9)
			(layers "F.Cu" "F.Mask" "F.Paste")
			(roundrect_rratio 0.25)
			(net 1 "GND")
			(pinfunction "GND")
			(pintype "power_in")
			(teardrops
				(best_length_ratio 0.2)
				(max_length 1)
				(best_width_ratio 0.9)
				(max_width 2)
				(curved_edges yes)
				(filter_ratio 0.9)
				(enabled yes)
				(allow_two_segments yes)
				(prefer_zone_connections yes)
			)
		)
		(pad "3" smd roundrect
			(at 0.723 0.925)
			(size 0.8 0.9)
			(layers "F.Cu" "F.Mask" "F.Paste")
			(roundrect_rratio 0.25)
			(net 790 "Net-(U38-1A)")
			(pinfunction "OUT")
			(pintype "output")
			(teardrops
				(best_length_ratio 0.2)
				(max_length 1)
				(best_width_ratio 0.9)
				(max_width 2)
				(curved_edges yes)
				(filter_ratio 0.9)
				(enabled yes)
				(allow_two_segments yes)
				(prefer_zone_connections yes)
			)
		)
		(pad "4" smd roundrect
			(at 0.723 -0.927)
			(size 0.8 0.9)
			(layers "F.Cu" "F.Mask" "F.Paste")
			(roundrect_rratio 0.25)
			(net 2 "+3V3")
			(pinfunction "VDD")
			(pintype "power_in")
			(teardrops
				(best_length_ratio 0.2)
				(max_length 1)
				(best_width_ratio 0.9)
				(max_width 2)
				(curved_edges yes)
				(filter_ratio 0.9)
				(enabled yes)
				(allow_two_segments yes)
				(prefer_zone_connections yes)
			)
		)
	)
	(footprint "antmicro-footprints:TP_SMD_0.75mm"
		(layer "F.Cu")
		(at 136.24 128.71)
		(property "Reference" "TP86"
			(at 0.51 -3.3 90)
			(layer "F.SilkS")
			(effects
				(font
					(size 0.7 0.7)
					(thickness 0.15)
				)
				(justify left bottom)
			)
		)
		(property "Value" "TP_0.75mm_SMD"
			(at 0 1.2 0)
			(layer "F.Fab")
			(effects
				(font
					(size 0.7 0.7)
					(thickness 0.15)
				)
				(justify left bottom)
			)
		)
		(property "Author" "Antmicro"
			(at 0 0 0)
			(layer "F.Fab")
			(hide yes)
			(effects
				(font
					(size 1 1)
					(thickness 0.15)
				)
			)
		)
		(property "License" "Apache-2.0"
			(at 0 0 0)
			(layer "F.Fab")
			(hide yes)
			(effects
				(font
					(size 1 1)
					(thickness 0.15)
				)
			)
		)
		(property "MPN" ""
			(at 0 0 0)
			(layer "F.Fab")
			(hide yes)
			(effects
				(font
					(size 1 1)
					(thickness 0.15)
				)
			)
		)
		(property "Manufacturer" ""
			(at 0 0 0)
			(layer "F.Fab")
			(hide yes)
			(effects
				(font
					(size 1 1)
					(thickness 0.15)
				)
			)
		)
		(property "Public" "False"
			(at 0 0 0)
			(layer "F.Fab")
			(hide yes)
			(effects
				(font
					(size 1 1)
					(thickness 0.15)
				)
			)
		)
		(sheetname "KR to SFI #2")
		(sheetfile "kr_sfi.kicad_sch")
		(attr exclude_from_pos_files exclude_from_bom)
		(fp_circle
			(center 0 0)
			(end 0.475 0)
			(stroke
				(width 0.05)
				(type default)
			)
			(fill no)
			(layer "F.CrtYd")
		)
		(pad "1" smd circle
			(at 0 0)
			(size 0.75 0.75)
			(layers "F.Cu" "F.Mask")
			(net 749 "Net-(U45C-AMUXB)")
			(pinfunction "1")
			(pintype "passive")
			(teardrops
				(best_length_ratio 0.4)
				(max_length 1)
				(best_width_ratio 0.9)
				(max_width 2)
				(curved_edges yes)
				(filter_ratio 0.9)
				(enabled yes)
				(allow_two_segments yes)
				(prefer_zone_connections yes)
			)
		)
	)
	(footprint "antmicro-footprints:R_0603_1608Metric"
		(layer "F.Cu")
		(at 180.13 90.1)
		(descr "Resistor SMD 0603")
		(tags "resistor SMD 0603")
		(property "Reference" "R125"
			(at 1.25 0.45 0)
			(layer "F.SilkS")
			(effects
				(font
					(size 0.7 0.7)
					(thickness 0.15)
				)
				(justify left bottom)
			)
		)
		(property "Value" "R_0R_22.4A_0603"
			(at 0 1.6 0)
			(layer "F.Fab")
			(effects
				(font
					(size 0.7 0.7)
					(thickness 0.15)
				)
				(justify left bottom)
			)
		)
		(property "Datasheet" "https://fscdn.rohm.com/en/products/databook/datasheet/passive/resistor/chip_resistor/pmr-jpw-e.pdf"
			(at 0 0 0)
			(layer "F.Fab")
			(hide yes)
			(effects
				(font
					(size 1.27 1.27)
					(thickness 0.15)
				)
			)
		)
		(property "Author" "Antmicro"
			(at 270.31 -88.19 90)
			(layer "F.Fab")
			(hide yes)
			(effects
				(font
					(size 1 1)
					(thickness 0.15)
				)
			)
		)
		(property "License" "Apache-2.0"
			(at 270.31 -88.19 90)
			(layer "F.Fab")
			(hide yes)
			(effects
				(font
					(size 1 1)
					(thickness 0.15)
				)
			)
		)
		(property "MPN" "PMR03EZPJ000"
			(at 270.31 -88.19 90)
			(layer "F.Fab")
			(hide yes)
			(effects
				(font
					(size 1 1)
					(thickness 0.15)
				)
			)
		)
		(property "Manufacturer" "ROHM Semiconductor"
			(at 270.31 -88.19 90)
			(layer "F.Fab")
			(hide yes)
			(effects
				(font
					(size 1 1)
					(thickness 0.15)
				)
			)
		)
		(property "Max. Curr." "22.4A"
			(at 270.31 -88.19 90)
			(layer "F.Fab")
			(hide yes)
			(effects
				(font
					(size 1 1)
					(thickness 0.15)
				)
			)
		)
		(property "Public" "False"
			(at 270.31 -88.19 90)
			(layer "F.Fab")
			(hide yes)
			(effects
				(font
					(size 1 1)
					(thickness 0.15)
				)
			)
		)
		(property "Tolerance" "template_tolerance"
			(at 270.31 -88.19 90)
			(layer "F.Fab")
			(hide yes)
			(effects
				(font
					(size 1 1)
					(thickness 0.15)
				)
			)
		)
		(property "Val" "0R"
			(at 270.31 -88.19 90)
			(layer "F.Fab")
			(hide yes)
			(effects
				(font
					(size 1 1)
					(thickness 0.15)
				)
			)
		)
		(sheetname "M.2 key M #1")
		(sheetfile "m2keym_low.kicad_sch")
		(attr smd)
		(fp_line
			(start -0.15 -0.4)
			(end 0.15 -0.4)
			(stroke
				(width 0.15)
				(type solid)
			)
			(layer "F.SilkS")
		)
		(fp_line
			(start -0.15 0.4)
			(end 0.15 0.4)
			(stroke
				(width 0.15)
				(type solid)
			)
			(layer "F.SilkS")
		)
		(fp_rect
			(start -1.25 -0.65)
			(end 1.25 0.65)
			(stroke
				(width 0.05)
				(type solid)
			)
			(fill no)
			(layer "F.CrtYd")
		)
		(fp_rect
			(start -0.8 -0.4)
			(end 0.8 0.4)
			(stroke
				(width 0.15)
				(type solid)
			)
			(fill no)
			(layer "F.Fab")
		)
		(pad "1" smd roundrect
			(at -0.7 0)
			(size 0.8 1)
			(layers "F.Cu" "F.Mask" "F.Paste")
			(roundrect_rratio 0.2)
			(net 969 "/M.2 key M #1/M2_3V3")
			(pintype "passive")
			(teardrops
				(best_length_ratio 0.2)
				(max_length 1)
				(best_width_ratio 0.9)
				(max_width 2)
				(curved_edges yes)
				(filter_ratio 0.9)
				(enabled yes)
				(allow_two_segments yes)
				(prefer_zone_connections yes)
			)
		)
		(pad "2" smd roundrect
			(at 0.7 0)
			(size 0.8 1)
			(layers "F.Cu" "F.Mask" "F.Paste")
			(roundrect_rratio 0.2)
			(net 2 "+3V3")
			(pintype "passive")
			(teardrops
				(best_length_ratio 0.2)
				(max_length 1)
				(best_width_ratio 0.9)
				(max_width 2)
				(curved_edges yes)
				(filter_ratio 0.9)
				(enabled yes)
				(allow_two_segments yes)
				(prefer_zone_connections yes)
			)
		)
	)
	(footprint "antmicro-footprints:R_0402_1005Metric"
		(layer "F.Cu")
		(at 190.762015 139.479219 -135)
		(descr "Resistor SMD 0402")
		(tags "resistor SMD 0402")
		(property "Reference" "R227"
			(at 1.119206 -0.465818 45)
			(layer "F.SilkS")
			(effects
				(font
					(size 0.7 0.7)
					(thickness 0.15)
				)
				(justify right bottom)
			)
		)
		(property "Value" "R_1k_0402"
			(at -1.011843 1.772046 45)
			(layer "F.Fab")
			(effects
				(font
					(size 0.7 0.7)
					(thickness 0.15)
				)
				(justify right bottom)
			)
		)
		(property "Datasheet" "https://www.bourns.com/docs/product-datasheets/cr.pdf"
			(at 0 0 45)
			(layer "B.Fab")
			(hide yes)
			(effects
				(font
					(size 1.27 1.27)
					(thickness 0.15)
				)
				(justify mirror)
			)
		)
		(property "Author" "Antmicro"
			(at 0 0 45)
			(layer "F.Fab")
			(hide yes)
			(effects
				(font
					(size 1 1)
					(thickness 0.15)
				)
			)
		)
		(property "License" "Apache-2.0"
			(at 0 0 45)
			(layer "F.Fab")
			(hide yes)
			(effects
				(font
					(size 1 1)
					(thickness 0.15)
				)
			)
		)
		(property "MPN" "CR0402-FX-1001GLF"
			(at 0 0 45)
			(layer "F.Fab")
			(hide yes)
			(effects
				(font
					(size 1 1)
					(thickness 0.15)
				)
			)
		)
		(property "Manufacturer" "Bourns"
			(at 0 0 45)
			(layer "F.Fab")
			(hide yes)
			(effects
				(font
					(size 1 1)
					(thickness 0.15)
				)
			)
		)
		(property "Public" "False"
			(at 0 0 45)
			(layer "F.Fab")
			(hide yes)
			(effects
				(font
					(size 1 1)
					(thickness 0.15)
				)
			)
		)
		(property "Tolerance" "1%"
			(at 0 0 45)
			(layer "F.Fab")
			(hide yes)
			(effects
				(font
					(size 1 1)
					(thickness 0.15)
				)
			)
		)
		(property "Val" "1k"
			(at 0 0 45)
			(layer "F.Fab")
			(hide yes)
			(effects
				(font
					(size 1 1)
					(thickness 0.15)
				)
			)
		)
		(sheetname "PCIe redriver")
		(sheetfile "pcie_redriver.kicad_sch")
		(attr smd dnp)
		(fp_poly
			(pts
				(xy -0.925 -0.47) (xy 0.925 -0.47) (xy 0.925 0.47) (xy -0.925 0.47)
			)
			(stroke
				(width 0.05)
				(type default)
			)
			(fill no)
			(layer "F.CrtYd")
		)
		(fp_poly
			(pts
				(xy -0.5 -0.25) (xy 0.5 -0.25) (xy 0.5 0.25) (xy -0.5 0.25)
			)
			(stroke
				(width 0.15)
				(type solid)
			)
			(fill no)
			(layer "F.Fab")
		)
		(pad "1" smd roundrect
			(at -0.48 0 225)
			(size 0.59 0.64)
			(layers "F.Cu" "F.Mask" "F.Paste")
			(roundrect_rratio 0.25)
			(net 2 "+3V3")
			(pintype "passive")
			(teardrops
				(best_length_ratio 0.2)
				(max_length 1)
				(best_width_ratio 0.9)
				(max_width 2)
				(curved_edges yes)
				(filter_ratio 0.9)
				(enabled yes)
				(allow_two_segments yes)
				(prefer_zone_connections yes)
			)
		)
		(pad "2" smd roundrect
			(at 0.48 0 225)
			(size 0.59 0.64)
			(layers "F.Cu" "F.Mask" "F.Paste")
			(roundrect_rratio 0.25)
			(net 977 "/PCIe redriver/RX_EQ1")
			(pintype "passive")
			(teardrops
				(best_length_ratio 0.2)
				(max_length 1)
				(best_width_ratio 0.9)
				(max_width 2)
				(curved_edges yes)
				(filter_ratio 0.9)
				(enabled yes)
				(allow_two_segments yes)
				(prefer_zone_connections yes)
			)
		)
	)
)
